(kicad_pcb
	(version 20260206)
	(generator "pcbnew")
	(generator_version "10.0")
	(general
		(thickness 1.6)
		(legacy_teardrops no)
	)
	(paper "A4")
	(title_block
		(title "04192023_DAF0TMB3IC0_F0TG_MB_C_brd_V02_OCP.brd")
		(comment 1 "Grand Teton / footprints 3355-3358 of 8354")
	)
	(layers
		(0 "F.Cu" signal "TOP")
		(4 "In1.Cu" signal "GND")
		(6 "In2.Cu" signal "IN1")
		(8 "In3.Cu" signal "GND1")
		(10 "In4.Cu" signal "IN2")
		(12 "In5.Cu" signal "GND2")
		(14 "In6.Cu" signal "IN3")
		(16 "In7.Cu" signal "GND3")
		(18 "In8.Cu" signal "VCC")
		(20 "In9.Cu" signal "VCC1")
		(22 "In10.Cu" signal "GND4")
		(24 "In11.Cu" signal "IN4")
		(26 "In12.Cu" signal "GND5")
		(28 "In13.Cu" signal "IN5")
		(30 "In14.Cu" signal "GND6")
		(32 "In15.Cu" signal "IN6")
		(34 "In16.Cu" signal "GND7")
		(2 "B.Cu" signal "BOTTOM")
		(9 "F.Adhes" user "F.Adhesive")
		(11 "B.Adhes" user "B.Adhesive")
		(13 "F.Paste" user "Package Geometry/Pastemask Top")
		(15 "B.Paste" user "Package Geometry/Pastemask Bottom")
		(5 "F.SilkS" user "Ref Des/Silkscreen Top")
		(7 "B.SilkS" user "Ref Des/Silkscreen Bottom")
		(1 "F.Mask" user "Board Geometry/Soldermask Top")
		(3 "B.Mask" user "Board Geometry/Soldermask Bottom")
		(17 "Dwgs.User" user "User.Drawings")
		(19 "Cmts.User" user "User.Comments")
		(21 "Eco1.User" user "User.Eco1")
		(23 "Eco2.User" user "User.Eco2")
		(25 "Edge.Cuts" user "Board Geometry/Outline")
		(27 "Margin" user)
		(31 "F.CrtYd" user "Package Geometry/Place Bound Top")
		(29 "B.CrtYd" user "Package Geometry/Place Bound Bottom")
		(35 "F.Fab" user "Ref Des/Assembly Top")
		(33 "B.Fab" user "Ref Des/Assembly Bottom")
	)
	(footprint ""
		(layer "F.Cu")
		(at 177.694082 -28.937712 -90)
		(property "Reference" "PU299"
			(at -4.293616 -3.376676 0)
			(unlocked yes)
			(layer "F.SilkS")
			(effects
				(font
					(size 0.7874 0.5842)
					(thickness 0.1524)
				)
				(justify left)
			)
		)
		(property "Value" ""
			(at 0 0 270)
			(layer "F.Fab")
			(effects
				(font
					(size 1.27 1.27)
				)
			)
		)
		(duplicate_pad_numbers_are_jumpers no)
		(fp_line
			(start -1.549908 2.549906)
			(end -0.753872 2.549906)
			(stroke
				(width 0.1524)
				(type default)
			)
			(layer "F.SilkS")
		)
		(fp_line
			(start -0.245872 2.549906)
			(end 0.245872 2.549906)
			(stroke
				(width 0.1524)
				(type default)
			)
			(layer "F.SilkS")
		)
		(fp_line
			(start 0.753872 2.549906)
			(end 1.549908 2.549906)
			(stroke
				(width 0.1524)
				(type default)
			)
			(layer "F.SilkS")
		)
		(fp_line
			(start 1.549908 2.549906)
			(end 1.549908 2.253996)
			(stroke
				(width 0.1524)
				(type default)
			)
			(layer "F.SilkS")
		)
		(fp_line
			(start -1.549908 2.253996)
			(end -1.549908 2.549906)
			(stroke
				(width 0.1524)
				(type default)
			)
			(layer "F.SilkS")
		)
		(fp_line
			(start 1.549908 -2.253996)
			(end 1.549908 -2.549906)
			(stroke
				(width 0.1524)
				(type default)
			)
			(layer "F.SilkS")
		)
		(fp_line
			(start -1.549908 -2.549906)
			(end -1.549908 -2.251964)
			(stroke
				(width 0.1524)
				(type default)
			)
			(layer "F.SilkS")
		)
		(fp_line
			(start -0.752094 -2.549906)
			(end -1.549908 -2.549906)
			(stroke
				(width 0.1524)
				(type default)
			)
			(layer "F.SilkS")
		)
		(fp_line
			(start 0.2413 -2.549906)
			(end -0.2413 -2.549906)
			(stroke
				(width 0.1524)
				(type default)
			)
			(layer "F.SilkS")
		)
		(fp_line
			(start 1.549908 -2.549906)
			(end 0.752094 -2.549906)
			(stroke
				(width 0.1524)
				(type default)
			)
			(layer "F.SilkS")
		)
		(fp_poly
			(pts
				(xy -2.418842 -3.085338) (xy -2.007616 -2.226564) (xy -2.94132 -2.413)
			)
			(stroke
				(width 0)
				(type default)
			)
			(fill yes)
			(layer "F.SilkS")
		)
		(fp_line
			(start -1.549908 2.549906)
			(end 1.549908 2.549906)
			(stroke
				(width 0.1)
				(type default)
			)
			(layer "F.Fab")
		)
		(fp_line
			(start 1.549908 2.549906)
			(end 1.549908 -2.549906)
			(stroke
				(width 0.1)
				(type default)
			)
			(layer "F.Fab")
		)
		(fp_line
			(start -1.549908 -2.549906)
			(end -1.549908 2.549906)
			(stroke
				(width 0.1)
				(type default)
			)
			(layer "F.Fab")
		)
		(fp_line
			(start 1.549908 -2.549906)
			(end -1.549908 -2.549906)
			(stroke
				(width 0.1)
				(type default)
			)
			(layer "F.Fab")
		)
		(fp_poly
			(pts
				(xy -1.891538 -1.999996) (xy -2.7432 -1.574292) (xy -2.7432 -2.4257)
			)
			(stroke
				(width 0)
				(type default)
			)
			(fill yes)
			(layer "F.Fab")
		)
		(fp_text user "11"
			(at 1.1938 7.393432 270)
			(unlocked yes)
			(layer "F.SilkS")
			(effects
				(font
					(size 0.635 0.4064)
					(thickness 0.1524)
				)
			)
		)
		(fp_text user "10"
			(at -1.4224 3.189732 270)
			(unlocked yes)
			(layer "F.SilkS")
			(effects
				(font
					(size 0.635 0.4064)
					(thickness 0.1524)
				)
			)
		)
		(fp_text user "12"
			(at 2.040636 2.75082 180)
			(unlocked yes)
			(layer "F.SilkS")
			(effects
				(font
					(size 0.635 0.4064)
					(thickness 0.1524)
				)
			)
		)
		(fp_text user "9"
			(at -2.592832 2.0828 180)
			(unlocked yes)
			(layer "F.SilkS")
			(effects
				(font
					(size 0.635 0.4064)
					(thickness 0.1524)
				)
			)
		)
		(fp_text user "20"
			(at 3.833368 -2.3876 180)
			(unlocked yes)
			(layer "F.SilkS")
			(effects
				(font
					(size 0.635 0.4064)
					(thickness 0.1524)
				)
			)
		)
		(fp_text user "21_22"
			(at -0.0762 -3.655568 270)
			(unlocked yes)
			(layer "F.SilkS")
			(effects
				(font
					(size 0.635 0.4064)
					(thickness 0.1524)
				)
			)
		)
		(fp_text user "11"
			(at 1.1938 3.329432 270)
			(unlocked yes)
			(layer "F.Fab")
			(effects
				(font
					(size 0.635 0.4064)
					(thickness 0.1524)
				)
			)
		)
		(fp_text user "10"
			(at -1.4224 3.253232 270)
			(unlocked yes)
			(layer "F.Fab")
			(effects
				(font
					(size 0.635 0.4064)
					(thickness 0.1524)
				)
			)
		)
		(fp_text user "12"
			(at 2.207768 2.7178 180)
			(unlocked yes)
			(layer "F.Fab")
			(effects
				(font
					(size 0.635 0.4064)
					(thickness 0.1524)
				)
			)
		)
		(fp_text user "9"
			(at -2.338832 2.5908 180)
			(unlocked yes)
			(layer "F.Fab")
			(effects
				(font
					(size 0.635 0.4064)
					(thickness 0.1524)
				)
			)
		)
		(fp_text user "20"
			(at 2.055368 -2.7686 180)
			(unlocked yes)
			(layer "F.Fab")
			(effects
				(font
					(size 0.635 0.4064)
					(thickness 0.1524)
				)
			)
		)
		(fp_text user "21_22"
			(at -0.0762 -3.401568 270)
			(unlocked yes)
			(layer "F.Fab")
			(effects
				(font
					(size 0.635 0.4064)
					(thickness 0.1524)
				)
			)
		)
		(pad "1" smd circle
			(at -1.374902 -1.999996 180)
			(size 0 0)
			(layers "F.Cu" "F.Mask" "F.Paste")
			(net "P12V_SCM_EN_R2")
		)
		(pad "2" smd rect
			(at -1.400048 -1.500124 180)
			(size 0.254 0.8128)
			(layers "F.Cu" "F.Mask" "F.Paste")
			(net "GND")
		)
		(pad "3" smd rect
			(at -1.400048 -0.999998 180)
			(size 0.254 0.8128)
			(layers "F.Cu" "F.Mask" "F.Paste")
			(net "GND")
		)
		(pad "4" smd rect
			(at -1.400048 -0.499872 180)
			(size 0.254 0.8128)
			(layers "F.Cu" "F.Mask" "F.Paste")
			(net "P12V_SCM_TIMER")
		)
		(pad "5" smd rect
			(at -1.400048 0 180)
			(size 0.254 0.8128)
			(layers "F.Cu" "F.Mask" "F.Paste")
			(net "P12V_SCM_ISET")
		)
		(pad "6" smd rect
			(at -1.400048 0.499872 180)
			(size 0.254 0.8128)
			(layers "F.Cu" "F.Mask" "F.Paste")
			(net "P12V_SCM_SS")
		)
		(pad "7" smd rect
			(at -1.400048 0.999998 180)
			(size 0.254 0.8128)
			(layers "F.Cu" "F.Mask" "F.Paste")
			(net "GND")
		)
		(pad "8" smd rect
			(at -1.400048 1.500124 180)
			(size 0.254 0.8128)
			(layers "F.Cu" "F.Mask" "F.Paste")
			(net "P12V_SCM_IMON")
		)
		(pad "9" smd rect
			(at -1.400048 1.999996 180)
			(size 0.254 0.8128)
			(layers "F.Cu" "F.Mask" "F.Paste")
			(net "P12V_SCM_FLTB_N")
		)
		(pad "10" smd rect
			(at -0.499872 2.400046 270)
			(size 0.254 0.8128)
			(layers "F.Cu" "F.Mask" "F.Paste")
			(net "HP_LVC3_SCM_HSC_PWRGD_R")
		)
		(pad "11" smd rect
			(at 0.499872 2.400046 270)
			(size 0.254 0.8128)
			(layers "F.Cu" "F.Mask" "F.Paste")
			(net "P12V_SCM_OV_FB")
		)
		(pad "12" smd rect
			(at 1.400048 1.999996 180)
			(size 0.254 0.8128)
			(layers "F.Cu" "F.Mask" "F.Paste")
			(net "P12V_SCM_AVIN_PD")
		)
		(pad "13" smd rect
			(at 1.400048 1.500124 180)
			(size 0.254 0.8128)
			(layers "F.Cu" "F.Mask" "F.Paste")
			(net "P12V_SCM_R")
		)
		(pad "14" smd rect
			(at 1.400048 0.999998 180)
			(size 0.254 0.8128)
			(layers "F.Cu" "F.Mask" "F.Paste")
			(net "P12V_SCM_R")
		)
		(pad "15" smd rect
			(at 1.400048 0.499872 180)
			(size 0.254 0.8128)
			(layers "F.Cu" "F.Mask" "F.Paste")
			(net "P12V_SCM_R")
		)
		(pad "16" smd rect
			(at 1.400048 0 180)
			(size 0.254 0.8128)
			(layers "F.Cu" "F.Mask" "F.Paste")
			(net "P12V_SCM_R")
		)
		(pad "17" smd rect
			(at 1.400048 -0.499872 180)
			(size 0.254 0.8128)
			(layers "F.Cu" "F.Mask" "F.Paste")
			(net "P12V_SCM_R")
		)
		(pad "18" smd rect
			(at 1.400048 -0.999998 180)
			(size 0.254 0.8128)
			(layers "F.Cu" "F.Mask" "F.Paste")
			(net "P12V_SCM_R")
		)
		(pad "19" smd rect
			(at 1.400048 -1.500124 180)
			(size 0.254 0.8128)
			(layers "F.Cu" "F.Mask" "F.Paste")
			(net "P12V_SCM_R")
		)
		(pad "20" smd rect
			(at 1.400048 -1.999996 180)
			(size 0.254 0.8128)
			(layers "F.Cu" "F.Mask" "F.Paste")
			(net "P12V_SCM_R")
		)
		(pad "21_22" smd circle
			(at 0.499872 -2.337562 180)
			(size 0 0)
			(layers "F.Cu" "F.Mask" "F.Paste")
			(net "P12V_AUX")
		)
		(pad "23" smd rect
			(at 0 -1.100074 180)
			(size 0.254 1.27)
			(layers "F.Cu" "F.Mask" "F.Paste")
			(net "P12V_AUX")
		)
		(pad "24" smd rect
			(at 0 -0.199898 180)
			(size 0.254 1.27)
			(layers "F.Cu" "F.Mask" "F.Paste")
			(net "P12V_AUX")
		)
		(pad "25" smd rect
			(at 0 0.700024 180)
			(size 0.254 1.27)
			(layers "F.Cu" "F.Mask" "F.Paste")
			(net "P12V_AUX")
		)
		(pad "26" smd rect
			(at 0 1.599946 180)
			(size 0.254 1.27)
			(layers "F.Cu" "F.Mask" "F.Paste")
			(net "P12V_AUX")
		)
	)
	(footprint ""
		(layer "F.Cu")
		(at 339.238844 -381.41783 -90)
		(property "Reference" "C954"
			(at 0 0 270)
			(layer "F.SilkS")
			(hide yes)
			(effects
				(font
					(size 1.27 1.27)
				)
			)
		)
		(property "Value" ""
			(at 0 0 270)
			(layer "F.Fab")
			(effects
				(font
					(size 1.27 1.27)
				)
			)
		)
		(duplicate_pad_numbers_are_jumpers no)
		(fp_line
			(start -0.299974 0.150114)
			(end -0.299974 -0.150114)
			(stroke
				(width 0.1)
				(type default)
			)
			(layer "F.Fab")
		)
		(fp_line
			(start 0.299974 0.150114)
			(end -0.299974 0.150114)
			(stroke
				(width 0.1)
				(type default)
			)
			(layer "F.Fab")
		)
		(fp_line
			(start -0.299974 -0.150114)
			(end 0.299974 -0.150114)
			(stroke
				(width 0.1)
				(type default)
			)
			(layer "F.Fab")
		)
		(fp_line
			(start 0.299974 -0.150114)
			(end 0.299974 0.150114)
			(stroke
				(width 0.1)
				(type default)
			)
			(layer "F.Fab")
		)
		(pad "1" smd rect
			(at -0.2667 0 270)
			(size 0.3048 0.381)
			(layers "F.Cu" "F.Mask" "F.Paste")
			(net "P5E_CPU0_P1_TX_C_DN<5>")
		)
		(pad "2" smd rect
			(at 0.2667 0 270)
			(size 0.3048 0.381)
			(layers "F.Cu" "F.Mask" "F.Paste")
			(net "P5E_CPU0_P1_TX_DN<5>")
		)
	)
	(footprint ""
		(layer "F.Cu")
		(at 63.194438 -28.382722)
		(property "Reference" "R3848"
			(at 0 0 0)
			(layer "F.SilkS")
			(hide yes)
			(effects
				(font
					(size 1.27 1.27)
				)
			)
		)
		(property "Value" ""
			(at 0 0 0)
			(layer "F.Fab")
			(effects
				(font
					(size 1.27 1.27)
				)
			)
		)
		(duplicate_pad_numbers_are_jumpers no)
		(fp_line
			(start -0.7874 -0.4064)
			(end 0.7874 -0.4064)
			(stroke
				(width 0.1524)
				(type default)
			)
			(layer "F.SilkS")
		)
		(fp_line
			(start -0.7874 0.4064)
			(end -0.7874 -0.4064)
			(stroke
				(width 0.1524)
				(type default)
			)
			(layer "F.SilkS")
		)
		(fp_line
			(start 0.7874 -0.4064)
			(end 0.7874 0.4064)
			(stroke
				(width 0.1524)
				(type default)
			)
			(layer "F.SilkS")
		)
		(fp_line
			(start 0.7874 0.4064)
			(end -0.7874 0.4064)
			(stroke
				(width 0.1524)
				(type default)
			)
			(layer "F.SilkS")
		)
		(fp_line
			(start -0.67945 -0.305054)
			(end -0.12065 -0.305054)
			(stroke
				(width 0.1)
				(type default)
			)
			(layer "F.Fab")
		)
		(fp_line
			(start -0.67945 0.3048)
			(end -0.67945 -0.305054)
			(stroke
				(width 0.1)
				(type default)
			)
			(layer "F.Fab")
		)
		(fp_line
			(start -0.12065 -0.305054)
			(end -0.12065 -0.2794)
			(stroke
				(width 0.1)
				(type default)
			)
			(layer "F.Fab")
		)
		(fp_line
			(start -0.12065 -0.2794)
			(end 0.12065 -0.2794)
			(stroke
				(width 0.1)
				(type default)
			)
			(layer "F.Fab")
		)
		(fp_line
			(start -0.12065 0.2794)
			(end -0.12065 0.3048)
			(stroke
				(width 0.1)
				(type default)
			)
			(layer "F.Fab")
		)
		(fp_line
			(start -0.12065 0.3048)
			(end -0.67945 0.3048)
			(stroke
				(width 0.1)
				(type default)
			)
			(layer "F.Fab")
		)
		(fp_line
			(start 0.120396 0.2794)
			(end -0.12065 0.2794)
			(stroke
				(width 0.1)
				(type default)
			)
			(layer "F.Fab")
		)
		(fp_line
			(start 0.120396 0.3048)
			(end 0.120396 0.2794)
			(stroke
				(width 0.1)
				(type default)
			)
			(layer "F.Fab")
		)
		(fp_line
			(start 0.12065 -0.3048)
			(end 0.67945 -0.3048)
			(stroke
				(width 0.1)
				(type default)
			)
			(layer "F.Fab")
		)
		(fp_line
			(start 0.12065 -0.2794)
			(end 0.12065 -0.3048)
			(stroke
				(width 0.1)
				(type default)
			)
			(layer "F.Fab")
		)
		(fp_line
			(start 0.67945 -0.3048)
			(end 0.67945 0.3048)
			(stroke
				(width 0.1)
				(type default)
			)
			(layer "F.Fab")
		)
		(fp_line
			(start 0.67945 0.3048)
			(end 0.120396 0.3048)
			(stroke
				(width 0.1)
				(type default)
			)
			(layer "F.Fab")
		)
		(pad "1" smd circle
			(at -0.40005 0)
			(size 0 0)
			(layers "F.Cu" "F.Mask" "F.Paste")
			(net "P3V3_AUX")
		)
		(pad "2" smd circle
			(at 0.40005 0)
			(size 0 0)
			(layers "F.Cu" "F.Mask" "F.Paste")
			(net "HP_LVC3_OCP_V3_2_P12V_PWRGD")
		)
	)
	(footprint ""
		(layer "F.Cu")
		(at 105.64876 -59.802268)
		(property "Reference" "R1731"
			(at 0 0 0)
			(layer "F.SilkS")
			(hide yes)
			(effects
				(font
					(size 1.27 1.27)
				)
			)
		)
		(property "Value" ""
			(at 0 0 0)
			(layer "F.Fab")
			(effects
				(font
					(size 1.27 1.27)
				)
			)
		)
		(duplicate_pad_numbers_are_jumpers no)
		(fp_line
			(start -0.7874 -0.4064)
			(end 0.7874 -0.4064)
			(stroke
				(width 0.1524)
				(type default)
			)
			(layer "F.SilkS")
		)
		(fp_line
			(start -0.7874 0.4064)
			(end -0.7874 -0.4064)
			(stroke
				(width 0.1524)
				(type default)
			)
			(layer "F.SilkS")
		)
		(fp_line
			(start 0.7874 -0.4064)
			(end 0.7874 0.4064)
			(stroke
				(width 0.1524)
				(type default)
			)
			(layer "F.SilkS")
		)
		(fp_line
			(start 0.7874 0.4064)
			(end -0.7874 0.4064)
			(stroke
				(width 0.1524)
				(type default)
			)
			(layer "F.SilkS")
		)
		(fp_line
			(start -0.67945 -0.305054)
			(end -0.12065 -0.305054)
			(stroke
				(width 0.1)
				(type default)
			)
			(layer "F.Fab")
		)
		(fp_line
			(start -0.67945 0.3048)
			(end -0.67945 -0.305054)
			(stroke
				(width 0.1)
				(type default)
			)
			(layer "F.Fab")
		)
		(fp_line
			(start -0.12065 -0.305054)
			(end -0.12065 -0.2794)
			(stroke
				(width 0.1)
				(type default)
			)
			(layer "F.Fab")
		)
		(fp_line
			(start -0.12065 -0.2794)
			(end 0.12065 -0.2794)
			(stroke
				(width 0.1)
				(type default)
			)
			(layer "F.Fab")
		)
		(fp_line
			(start -0.12065 0.2794)
			(end -0.12065 0.3048)
			(stroke
				(width 0.1)
				(type default)
			)
			(layer "F.Fab")
		)
		(fp_line
			(start -0.12065 0.3048)
			(end -0.67945 0.3048)
			(stroke
				(width 0.1)
				(type default)
			)
			(layer "F.Fab")
		)
		(fp_line
			(start 0.120396 0.2794)
			(end -0.12065 0.2794)
			(stroke
				(width 0.1)
				(type default)
			)
			(layer "F.Fab")
		)
		(fp_line
			(start 0.120396 0.3048)
			(end 0.120396 0.2794)
			(stroke
				(width 0.1)
				(type default)
			)
			(layer "F.Fab")
		)
		(fp_line
			(start 0.12065 -0.3048)
			(end 0.67945 -0.3048)
			(stroke
				(width 0.1)
				(type default)
			)
			(layer "F.Fab")
		)
		(fp_line
			(start 0.12065 -0.2794)
			(end 0.12065 -0.3048)
			(stroke
				(width 0.1)
				(type default)
			)
			(layer "F.Fab")
		)
		(fp_line
			(start 0.67945 -0.3048)
			(end 0.67945 0.3048)
			(stroke
				(width 0.1)
				(type default)
			)
			(layer "F.Fab")
		)
		(fp_line
			(start 0.67945 0.3048)
			(end 0.120396 0.3048)
			(stroke
				(width 0.1)
				(type default)
			)
			(layer "F.Fab")
		)
		(pad "1" smd circle
			(at -0.40005 0)
			(size 0 0)
			(layers "F.Cu" "F.Mask" "F.Paste")
			(net "P3V3_AUX")
		)
		(pad "2" smd circle
			(at 0.40005 0)
			(size 0 0)
			(layers "F.Cu" "F.Mask" "F.Paste")
			(net "JTAG_SCM_TMS")
		)
	)
)
